(kicad_pcb
	(version 20260206)
	(generator "pcbnew")
	(generator_version "10.0")
	(general
		(thickness 1.6)
		(legacy_teardrops no)
	)
	(paper "A4")
	(title_block
		(title "01162023_DA0F0TEBIF0_F0T_Expander_BD_F_brd_V02_OCP.brd")
		(comment 1 "Grand Teton / footprints 1929-1934 of 9728")
	)
	(layers
		(0 "F.Cu" signal "TOP")
		(4 "In1.Cu" signal "GND")
		(6 "In2.Cu" signal "VCC")
		(8 "In3.Cu" signal "VCC1")
		(10 "In4.Cu" signal "GND1")
		(12 "In5.Cu" signal "IN1")
		(14 "In6.Cu" signal "GND2")
		(16 "In7.Cu" signal "IN2")
		(18 "In8.Cu" signal "GND3")
		(20 "In9.Cu" signal "IN3")
		(22 "In10.Cu" signal "GND4")
		(24 "In11.Cu" signal "IN4")
		(26 "In12.Cu" signal "GND5")
		(28 "In13.Cu" signal "IN5")
		(30 "In14.Cu" signal "GND6")
		(32 "In15.Cu" signal "IN6")
		(34 "In16.Cu" signal "GND7")
		(2 "B.Cu" signal "BOTTOM")
		(9 "F.Adhes" user "F.Adhesive")
		(11 "B.Adhes" user "B.Adhesive")
		(13 "F.Paste" user "Package Geometry/Pastemask Top")
		(15 "B.Paste" user "Package Geometry/Pastemask Bottom")
		(5 "F.SilkS" user "Ref Des/Silkscreen Top")
		(7 "B.SilkS" user "Ref Des/Silkscreen Bottom")
		(1 "F.Mask" user "Board Geometry/Soldermask Top")
		(3 "B.Mask" user "Board Geometry/Soldermask Bottom")
		(17 "Dwgs.User" user "User.Drawings")
		(19 "Cmts.User" user "User.Comments")
		(21 "Eco1.User" user "User.Eco1")
		(23 "Eco2.User" user "User.Eco2")
		(25 "Edge.Cuts" user "Board Geometry/Outline")
		(27 "Margin" user)
		(31 "F.CrtYd" user "Package Geometry/Place Bound Top")
		(29 "B.CrtYd" user "Package Geometry/Place Bound Bottom")
		(35 "F.Fab" user "Ref Des/Assembly Top")
		(33 "B.Fab" user "Ref Des/Assembly Bottom")
	)
	(footprint ""
		(layer "F.Cu")
		(at 338.074 -151.003)
		(property "Reference" "R4830"
			(at 0 0 0)
			(layer "F.SilkS")
			(hide yes)
			(effects
				(font
					(size 1.27 1.27)
				)
			)
		)
		(property "Value" ""
			(at 0 0 0)
			(layer "F.Fab")
			(effects
				(font
					(size 1.27 1.27)
				)
			)
		)
		(duplicate_pad_numbers_are_jumpers no)
		(fp_line
			(start -0.7874 -0.4064)
			(end 0.7874 -0.4064)
			(stroke
				(width 0.1524)
				(type default)
			)
			(layer "F.SilkS")
		)
		(fp_line
			(start -0.7874 0.4064)
			(end -0.7874 -0.4064)
			(stroke
				(width 0.1524)
				(type default)
			)
			(layer "F.SilkS")
		)
		(fp_line
			(start 0.7874 -0.4064)
			(end 0.7874 0.4064)
			(stroke
				(width 0.1524)
				(type default)
			)
			(layer "F.SilkS")
		)
		(fp_line
			(start 0.7874 0.4064)
			(end -0.7874 0.4064)
			(stroke
				(width 0.1524)
				(type default)
			)
			(layer "F.SilkS")
		)
		(fp_line
			(start -0.67945 -0.305054)
			(end -0.12065 -0.305054)
			(stroke
				(width 0.1)
				(type default)
			)
			(layer "F.Fab")
		)
		(fp_line
			(start -0.67945 0.3048)
			(end -0.67945 -0.305054)
			(stroke
				(width 0.1)
				(type default)
			)
			(layer "F.Fab")
		)
		(fp_line
			(start -0.12065 -0.305054)
			(end -0.12065 -0.2794)
			(stroke
				(width 0.1)
				(type default)
			)
			(layer "F.Fab")
		)
		(fp_line
			(start -0.12065 -0.2794)
			(end 0.12065 -0.2794)
			(stroke
				(width 0.1)
				(type default)
			)
			(layer "F.Fab")
		)
		(fp_line
			(start -0.12065 0.2794)
			(end -0.12065 0.3048)
			(stroke
				(width 0.1)
				(type default)
			)
			(layer "F.Fab")
		)
		(fp_line
			(start -0.12065 0.3048)
			(end -0.67945 0.3048)
			(stroke
				(width 0.1)
				(type default)
			)
			(layer "F.Fab")
		)
		(fp_line
			(start 0.120396 0.2794)
			(end -0.12065 0.2794)
			(stroke
				(width 0.1)
				(type default)
			)
			(layer "F.Fab")
		)
		(fp_line
			(start 0.120396 0.3048)
			(end 0.120396 0.2794)
			(stroke
				(width 0.1)
				(type default)
			)
			(layer "F.Fab")
		)
		(fp_line
			(start 0.12065 -0.3048)
			(end 0.67945 -0.3048)
			(stroke
				(width 0.1)
				(type default)
			)
			(layer "F.Fab")
		)
		(fp_line
			(start 0.12065 -0.2794)
			(end 0.12065 -0.3048)
			(stroke
				(width 0.1)
				(type default)
			)
			(layer "F.Fab")
		)
		(fp_line
			(start 0.67945 -0.3048)
			(end 0.67945 0.3048)
			(stroke
				(width 0.1)
				(type default)
			)
			(layer "F.Fab")
		)
		(fp_line
			(start 0.67945 0.3048)
			(end 0.120396 0.3048)
			(stroke
				(width 0.1)
				(type default)
			)
			(layer "F.Fab")
		)
		(pad "1" smd circle
			(at -0.40005 0)
			(size 0 0)
			(layers "F.Cu" "F.Mask" "F.Paste")
			(net "PEX3_PCA9555_1_INT_N")
		)
		(pad "2" smd circle
			(at 0.40005 0)
			(size 0 0)
			(layers "F.Cu" "F.Mask" "F.Paste")
			(net "P1V8_PEX")
		)
	)
	(footprint ""
		(layer "F.Cu")
		(at 179.777644 -117.566186)
		(property "Reference" "R194"
			(at 0 0 0)
			(layer "F.SilkS")
			(hide yes)
			(effects
				(font
					(size 1.27 1.27)
				)
			)
		)
		(property "Value" ""
			(at 0 0 0)
			(layer "F.Fab")
			(effects
				(font
					(size 1.27 1.27)
				)
			)
		)
		(duplicate_pad_numbers_are_jumpers no)
		(fp_line
			(start -0.7874 -0.4064)
			(end 0.7874 -0.4064)
			(stroke
				(width 0.1524)
				(type default)
			)
			(layer "F.SilkS")
		)
		(fp_line
			(start -0.7874 0.4064)
			(end -0.7874 -0.4064)
			(stroke
				(width 0.1524)
				(type default)
			)
			(layer "F.SilkS")
		)
		(fp_line
			(start 0.7874 -0.4064)
			(end 0.7874 0.4064)
			(stroke
				(width 0.1524)
				(type default)
			)
			(layer "F.SilkS")
		)
		(fp_line
			(start 0.7874 0.4064)
			(end -0.7874 0.4064)
			(stroke
				(width 0.1524)
				(type default)
			)
			(layer "F.SilkS")
		)
		(fp_line
			(start -0.67945 -0.305054)
			(end -0.12065 -0.305054)
			(stroke
				(width 0.1)
				(type default)
			)
			(layer "F.Fab")
		)
		(fp_line
			(start -0.67945 0.3048)
			(end -0.67945 -0.305054)
			(stroke
				(width 0.1)
				(type default)
			)
			(layer "F.Fab")
		)
		(fp_line
			(start -0.12065 -0.305054)
			(end -0.12065 -0.2794)
			(stroke
				(width 0.1)
				(type default)
			)
			(layer "F.Fab")
		)
		(fp_line
			(start -0.12065 -0.2794)
			(end 0.12065 -0.2794)
			(stroke
				(width 0.1)
				(type default)
			)
			(layer "F.Fab")
		)
		(fp_line
			(start -0.12065 0.2794)
			(end -0.12065 0.3048)
			(stroke
				(width 0.1)
				(type default)
			)
			(layer "F.Fab")
		)
		(fp_line
			(start -0.12065 0.3048)
			(end -0.67945 0.3048)
			(stroke
				(width 0.1)
				(type default)
			)
			(layer "F.Fab")
		)
		(fp_line
			(start 0.120396 0.2794)
			(end -0.12065 0.2794)
			(stroke
				(width 0.1)
				(type default)
			)
			(layer "F.Fab")
		)
		(fp_line
			(start 0.120396 0.3048)
			(end 0.120396 0.2794)
			(stroke
				(width 0.1)
				(type default)
			)
			(layer "F.Fab")
		)
		(fp_line
			(start 0.12065 -0.3048)
			(end 0.67945 -0.3048)
			(stroke
				(width 0.1)
				(type default)
			)
			(layer "F.Fab")
		)
		(fp_line
			(start 0.12065 -0.2794)
			(end 0.12065 -0.3048)
			(stroke
				(width 0.1)
				(type default)
			)
			(layer "F.Fab")
		)
		(fp_line
			(start 0.67945 -0.3048)
			(end 0.67945 0.3048)
			(stroke
				(width 0.1)
				(type default)
			)
			(layer "F.Fab")
		)
		(fp_line
			(start 0.67945 0.3048)
			(end 0.120396 0.3048)
			(stroke
				(width 0.1)
				(type default)
			)
			(layer "F.Fab")
		)
		(pad "1" smd circle
			(at -0.40005 0)
			(size 0 0)
			(layers "F.Cu" "F.Mask" "F.Paste")
			(net "PRSNT_NIC3_N")
		)
		(pad "2" smd circle
			(at 0.40005 0)
			(size 0 0)
			(layers "F.Cu" "F.Mask" "F.Paste")
			(net "PRSNTB2_NIC3_N")
		)
	)
	(footprint ""
		(layer "F.Cu")
		(at 104.243632 -44.87291)
		(property "Reference" "R540"
			(at 0 0 0)
			(layer "F.SilkS")
			(hide yes)
			(effects
				(font
					(size 1.27 1.27)
				)
			)
		)
		(property "Value" ""
			(at 0 0 0)
			(layer "F.Fab")
			(effects
				(font
					(size 1.27 1.27)
				)
			)
		)
		(duplicate_pad_numbers_are_jumpers no)
		(fp_line
			(start -0.7874 -0.4064)
			(end 0.7874 -0.4064)
			(stroke
				(width 0.1524)
				(type default)
			)
			(layer "F.SilkS")
		)
		(fp_line
			(start -0.7874 0.4064)
			(end -0.7874 -0.4064)
			(stroke
				(width 0.1524)
				(type default)
			)
			(layer "F.SilkS")
		)
		(fp_line
			(start 0.7874 -0.4064)
			(end 0.7874 0.4064)
			(stroke
				(width 0.1524)
				(type default)
			)
			(layer "F.SilkS")
		)
		(fp_line
			(start 0.7874 0.4064)
			(end -0.7874 0.4064)
			(stroke
				(width 0.1524)
				(type default)
			)
			(layer "F.SilkS")
		)
		(fp_line
			(start -0.67945 -0.305054)
			(end -0.12065 -0.305054)
			(stroke
				(width 0.1)
				(type default)
			)
			(layer "F.Fab")
		)
		(fp_line
			(start -0.67945 0.3048)
			(end -0.67945 -0.305054)
			(stroke
				(width 0.1)
				(type default)
			)
			(layer "F.Fab")
		)
		(fp_line
			(start -0.12065 -0.305054)
			(end -0.12065 -0.2794)
			(stroke
				(width 0.1)
				(type default)
			)
			(layer "F.Fab")
		)
		(fp_line
			(start -0.12065 -0.2794)
			(end 0.12065 -0.2794)
			(stroke
				(width 0.1)
				(type default)
			)
			(layer "F.Fab")
		)
		(fp_line
			(start -0.12065 0.2794)
			(end -0.12065 0.3048)
			(stroke
				(width 0.1)
				(type default)
			)
			(layer "F.Fab")
		)
		(fp_line
			(start -0.12065 0.3048)
			(end -0.67945 0.3048)
			(stroke
				(width 0.1)
				(type default)
			)
			(layer "F.Fab")
		)
		(fp_line
			(start 0.120396 0.2794)
			(end -0.12065 0.2794)
			(stroke
				(width 0.1)
				(type default)
			)
			(layer "F.Fab")
		)
		(fp_line
			(start 0.120396 0.3048)
			(end 0.120396 0.2794)
			(stroke
				(width 0.1)
				(type default)
			)
			(layer "F.Fab")
		)
		(fp_line
			(start 0.12065 -0.3048)
			(end 0.67945 -0.3048)
			(stroke
				(width 0.1)
				(type default)
			)
			(layer "F.Fab")
		)
		(fp_line
			(start 0.12065 -0.2794)
			(end 0.12065 -0.3048)
			(stroke
				(width 0.1)
				(type default)
			)
			(layer "F.Fab")
		)
		(fp_line
			(start 0.67945 -0.3048)
			(end 0.67945 0.3048)
			(stroke
				(width 0.1)
				(type default)
			)
			(layer "F.Fab")
		)
		(fp_line
			(start 0.67945 0.3048)
			(end 0.120396 0.3048)
			(stroke
				(width 0.1)
				(type default)
			)
			(layer "F.Fab")
		)
		(pad "1" smd circle
			(at -0.40005 0)
			(size 0 0)
			(layers "F.Cu" "F.Mask" "F.Paste")
			(net "SSD3_ADC_A0")
		)
		(pad "2" smd circle
			(at 0.40005 0)
			(size 0 0)
			(layers "F.Cu" "F.Mask" "F.Paste")
			(net "P3V3_AUX")
		)
	)
	(footprint ""
		(layer "F.Cu")
		(at 223.50476 -312.316114 180)
		(property "Reference" "PC229"
			(at 0 0 180)
			(layer "F.SilkS")
			(hide yes)
			(effects
				(font
					(size 1.27 1.27)
				)
			)
		)
		(property "Value" ""
			(at 0 0 180)
			(layer "F.Fab")
			(effects
				(font
					(size 1.27 1.27)
				)
			)
		)
		(duplicate_pad_numbers_are_jumpers no)
		(fp_line
			(start 1.524 0.762)
			(end -1.524 0.762)
			(stroke
				(width 0.1524)
				(type default)
			)
			(layer "F.SilkS")
		)
		(fp_line
			(start 1.524 -0.762)
			(end 1.524 0.762)
			(stroke
				(width 0.1524)
				(type default)
			)
			(layer "F.SilkS")
		)
		(fp_line
			(start -1.524 0.762)
			(end -1.524 -0.762)
			(stroke
				(width 0.1524)
				(type default)
			)
			(layer "F.SilkS")
		)
		(fp_line
			(start -1.524 -0.762)
			(end 1.524 -0.762)
			(stroke
				(width 0.1524)
				(type default)
			)
			(layer "F.SilkS")
		)
		(fp_line
			(start 1.1049 0.724916)
			(end 1.1049 -0.724916)
			(stroke
				(width 0.1)
				(type default)
			)
			(layer "F.Fab")
		)
		(fp_line
			(start 1.1049 -0.724916)
			(end -1.1049 -0.724916)
			(stroke
				(width 0.1)
				(type default)
			)
			(layer "F.Fab")
		)
		(fp_line
			(start -1.1049 0.724916)
			(end 1.1049 0.724916)
			(stroke
				(width 0.1)
				(type default)
			)
			(layer "F.Fab")
		)
		(fp_line
			(start -1.1049 -0.724916)
			(end -1.1049 0.724916)
			(stroke
				(width 0.1)
				(type default)
			)
			(layer "F.Fab")
		)
		(pad "1" smd rect
			(at -0.889 0)
			(size 1.016 1.27)
			(layers "F.Cu" "F.Mask" "F.Paste")
			(net "SW_P12V_P1V25_PEX1_FLT")
		)
		(pad "2" smd rect
			(at 0.889 0)
			(size 1.016 1.27)
			(layers "F.Cu" "F.Mask" "F.Paste")
			(net "GND")
		)
	)
	(footprint ""
		(layer "F.Cu")
		(at 295.670732 -137.848848 180)
		(property "Reference" "R261"
			(at 0 0 180)
			(layer "F.SilkS")
			(hide yes)
			(effects
				(font
					(size 1.27 1.27)
				)
			)
		)
		(property "Value" ""
			(at 0 0 180)
			(layer "F.Fab")
			(effects
				(font
					(size 1.27 1.27)
				)
			)
		)
		(duplicate_pad_numbers_are_jumpers no)
		(fp_line
			(start 0.7874 0.4064)
			(end -0.7874 0.4064)
			(stroke
				(width 0.1524)
				(type default)
			)
			(layer "F.SilkS")
		)
		(fp_line
			(start 0.7874 -0.4064)
			(end 0.7874 0.4064)
			(stroke
				(width 0.1524)
				(type default)
			)
			(layer "F.SilkS")
		)
		(fp_line
			(start -0.7874 0.4064)
			(end -0.7874 -0.4064)
			(stroke
				(width 0.1524)
				(type default)
			)
			(layer "F.SilkS")
		)
		(fp_line
			(start -0.7874 -0.4064)
			(end 0.7874 -0.4064)
			(stroke
				(width 0.1524)
				(type default)
			)
			(layer "F.SilkS")
		)
		(fp_line
			(start 0.67945 0.3048)
			(end 0.120396 0.3048)
			(stroke
				(width 0.1)
				(type default)
			)
			(layer "F.Fab")
		)
		(fp_line
			(start 0.67945 -0.3048)
			(end 0.67945 0.3048)
			(stroke
				(width 0.1)
				(type default)
			)
			(layer "F.Fab")
		)
		(fp_line
			(start 0.12065 -0.2794)
			(end 0.12065 -0.3048)
			(stroke
				(width 0.1)
				(type default)
			)
			(layer "F.Fab")
		)
		(fp_line
			(start 0.12065 -0.3048)
			(end 0.67945 -0.3048)
			(stroke
				(width 0.1)
				(type default)
			)
			(layer "F.Fab")
		)
		(fp_line
			(start 0.120396 0.3048)
			(end 0.120396 0.2794)
			(stroke
				(width 0.1)
				(type default)
			)
			(layer "F.Fab")
		)
		(fp_line
			(start 0.120396 0.2794)
			(end -0.12065 0.2794)
			(stroke
				(width 0.1)
				(type default)
			)
			(layer "F.Fab")
		)
		(fp_line
			(start -0.12065 0.3048)
			(end -0.67945 0.3048)
			(stroke
				(width 0.1)
				(type default)
			)
			(layer "F.Fab")
		)
		(fp_line
			(start -0.12065 0.2794)
			(end -0.12065 0.3048)
			(stroke
				(width 0.1)
				(type default)
			)
			(layer "F.Fab")
		)
		(fp_line
			(start -0.12065 -0.2794)
			(end 0.12065 -0.2794)
			(stroke
				(width 0.1)
				(type default)
			)
			(layer "F.Fab")
		)
		(fp_line
			(start -0.12065 -0.305054)
			(end -0.12065 -0.2794)
			(stroke
				(width 0.1)
				(type default)
			)
			(layer "F.Fab")
		)
		(fp_line
			(start -0.67945 0.3048)
			(end -0.67945 -0.305054)
			(stroke
				(width 0.1)
				(type default)
			)
			(layer "F.Fab")
		)
		(fp_line
			(start -0.67945 -0.305054)
			(end -0.12065 -0.305054)
			(stroke
				(width 0.1)
				(type default)
			)
			(layer "F.Fab")
		)
		(pad "1" smd circle
			(at -0.40005 0 180)
			(size 0 0)
			(layers "F.Cu" "F.Mask" "F.Paste")
			(net "PRSNTB1_NIC5_N")
		)
		(pad "2" smd circle
			(at 0.40005 0 180)
			(size 0 0)
			(layers "F.Cu" "F.Mask" "F.Paste")
			(net "P3V3_AUX")
		)
	)
	(footprint ""
		(layer "F.Cu")
		(at 55.88 -138.6332 180)
		(property "Reference" "R41"
			(at 0 0 180)
			(layer "F.SilkS")
			(hide yes)
			(effects
				(font
					(size 1.27 1.27)
				)
			)
		)
		(property "Value" ""
			(at 0 0 180)
			(layer "F.Fab")
			(effects
				(font
					(size 1.27 1.27)
				)
			)
		)
		(duplicate_pad_numbers_are_jumpers no)
		(fp_line
			(start 0.7874 0.4064)
			(end -0.7874 0.4064)
			(stroke
				(width 0.1524)
				(type default)
			)
			(layer "F.SilkS")
		)
		(fp_line
			(start 0.7874 -0.4064)
			(end 0.7874 0.4064)
			(stroke
				(width 0.1524)
				(type default)
			)
			(layer "F.SilkS")
		)
		(fp_line
			(start -0.7874 0.4064)
			(end -0.7874 -0.4064)
			(stroke
				(width 0.1524)
				(type default)
			)
			(layer "F.SilkS")
		)
		(fp_line
			(start -0.7874 -0.4064)
			(end 0.7874 -0.4064)
			(stroke
				(width 0.1524)
				(type default)
			)
			(layer "F.SilkS")
		)
		(fp_line
			(start 0.67945 0.3048)
			(end 0.120396 0.3048)
			(stroke
				(width 0.1)
				(type default)
			)
			(layer "F.Fab")
		)
		(fp_line
			(start 0.67945 -0.3048)
			(end 0.67945 0.3048)
			(stroke
				(width 0.1)
				(type default)
			)
			(layer "F.Fab")
		)
		(fp_line
			(start 0.12065 -0.2794)
			(end 0.12065 -0.3048)
			(stroke
				(width 0.1)
				(type default)
			)
			(layer "F.Fab")
		)
		(fp_line
			(start 0.12065 -0.3048)
			(end 0.67945 -0.3048)
			(stroke
				(width 0.1)
				(type default)
			)
			(layer "F.Fab")
		)
		(fp_line
			(start 0.120396 0.3048)
			(end 0.120396 0.2794)
			(stroke
				(width 0.1)
				(type default)
			)
			(layer "F.Fab")
		)
		(fp_line
			(start 0.120396 0.2794)
			(end -0.12065 0.2794)
			(stroke
				(width 0.1)
				(type default)
			)
			(layer "F.Fab")
		)
		(fp_line
			(start -0.12065 0.3048)
			(end -0.67945 0.3048)
			(stroke
				(width 0.1)
				(type default)
			)
			(layer "F.Fab")
		)
		(fp_line
			(start -0.12065 0.2794)
			(end -0.12065 0.3048)
			(stroke
				(width 0.1)
				(type default)
			)
			(layer "F.Fab")
		)
		(fp_line
			(start -0.12065 -0.2794)
			(end 0.12065 -0.2794)
			(stroke
				(width 0.1)
				(type default)
			)
			(layer "F.Fab")
		)
		(fp_line
			(start -0.12065 -0.305054)
			(end -0.12065 -0.2794)
			(stroke
				(width 0.1)
				(type default)
			)
			(layer "F.Fab")
		)
		(fp_line
			(start -0.67945 0.3048)
			(end -0.67945 -0.305054)
			(stroke
				(width 0.1)
				(type default)
			)
			(layer "F.Fab")
		)
		(fp_line
			(start -0.67945 -0.305054)
			(end -0.12065 -0.305054)
			(stroke
				(width 0.1)
				(type default)
			)
			(layer "F.Fab")
		)
		(pad "1" smd circle
			(at -0.40005 0 180)
			(size 0 0)
			(layers "F.Cu" "F.Mask" "F.Paste")
			(net "PRSNT_NIC0_N")
		)
		(pad "2" smd circle
			(at 0.40005 0 180)
			(size 0 0)
			(layers "F.Cu" "F.Mask" "F.Paste")
			(net "PRSNTB2_NIC0_N")
		)
	)
)
